# T6G (Grand Teton) — schematic netlist excerpt (pin names and nets, part order shuffled) for the footprints in the layout excerpt that follows; sources: Cadence DE-HDL packaged netlist, KiCad conversion of 04192023_DAF0TMB3IC0_F0TG_MB_C_brd_V02_OCP.brd

C6597  Q_CAP_DIFFBUS  DIFF BUS_0.22UF 6.3V 20% X6S  pkg C0201  page 308 : \1\ = P5E_CPU0_P3_TX_BUF_C_DP<0> ; \2\ = P5E_CPU0_P3_TX_BUF_DP<0>
PC6025  Q_CAP  22UF 4V 20% X6S  pkg C0805  page 270 : A = P1V2_AUX ; B = GND
PC528  Q_CAPP  470UF 2.5V 20% SPCAP  pkg SMLF  page 225 : A = PVDD11_S3_P1 ; B = GND
C6730  Q_CAP_DIFFBUS  DIFF BUS_0.22UF 6.3V 20% X6S  pkg C0201  page 352 : \1\ = P5E_CPU1_P3_TX_BUF_C_DN<2> ; \2\ = P5E_CPU1_P3_TX_BUF_DN<2>

(kicad_pcb
	(version 20260206)
	(generator "pcbnew")
	(generator_version "10.0")
	(general
		(thickness 1.6)
		(legacy_teardrops no)
	)
	(paper "A4")
	(title_block
		(title "04192023_DAF0TMB3IC0_F0TG_MB_C_brd_V02_OCP.brd")
		(comment 1 "Grand Teton / footprints 6469-6472 of 8354")
	)
	(layers
		(0 "F.Cu" signal "TOP")
		(4 "In1.Cu" signal "GND")
		(6 "In2.Cu" signal "IN1")
		(8 "In3.Cu" signal "GND1")
		(10 "In4.Cu" signal "IN2")
		(12 "In5.Cu" signal "GND2")
		(14 "In6.Cu" signal "IN3")
		(16 "In7.Cu" signal "GND3")
		(18 "In8.Cu" signal "VCC")
		(20 "In9.Cu" signal "VCC1")
		(22 "In10.Cu" signal "GND4")
		(24 "In11.Cu" signal "IN4")
		(26 "In12.Cu" signal "GND5")
		(28 "In13.Cu" signal "IN5")
		(30 "In14.Cu" signal "GND6")
		(32 "In15.Cu" signal "IN6")
		(34 "In16.Cu" signal "GND7")
		(2 "B.Cu" signal "BOTTOM")
		(9 "F.Adhes" user "F.Adhesive")
		(11 "B.Adhes" user "B.Adhesive")
		(13 "F.Paste" user "Package Geometry/Pastemask Top")
		(15 "B.Paste" user "Package Geometry/Pastemask Bottom")
		(5 "F.SilkS" user "Ref Des/Silkscreen Top")
		(7 "B.SilkS" user "Ref Des/Silkscreen Bottom")
		(1 "F.Mask" user "Board Geometry/Soldermask Top")
		(3 "B.Mask" user "Board Geometry/Soldermask Bottom")
		(17 "Dwgs.User" user "User.Drawings")
		(19 "Cmts.User" user "User.Comments")
		(21 "Eco1.User" user "User.Eco1")
		(23 "Eco2.User" user "User.Eco2")
		(25 "Edge.Cuts" user "Board Geometry/Outline")
		(27 "Margin" user)
		(31 "F.CrtYd" user "Package Geometry/Place Bound Top")
		(29 "B.CrtYd" user "Package Geometry/Place Bound Bottom")
		(35 "F.Fab" user "Ref Des/Assembly Top")
		(33 "B.Fab" user "Ref Des/Assembly Bottom")
	)
	(footprint ""
		(layer "B.Cu")
		(at 191.196214 -344.177112 -90)
		(property "Reference" "PC528"
			(at 7.567676 -4.797806 270)
			(unlocked yes)
			(layer "B.SilkS")
			(effects
				(font
					(size 0.7874 0.5842)
					(thickness 0.1524)
				)
				(justify left mirror)
			)
		)
		(property "Value" ""
			(at 0 0 90)
			(layer "B.Fab")
			(effects
				(font
					(size 1.27 1.27)
				)
				(justify mirror)
			)
		)
		(duplicate_pad_numbers_are_jumpers no)
		(fp_line
			(start -4.533392 2.249932)
			(end 4.533392 2.249932)
			(stroke
				(width 0.1524)
				(type default)
			)
			(layer "B.SilkS")
		)
		(fp_line
			(start 4.533392 2.249932)
			(end 4.533392 -2.249932)
			(stroke
				(width 0.1524)
				(type default)
			)
			(layer "B.SilkS")
		)
		(fp_line
			(start -4.533392 -2.249932)
			(end -4.533392 2.249932)
			(stroke
				(width 0.1524)
				(type default)
			)
			(layer "B.SilkS")
		)
		(fp_line
			(start 4.533392 -2.249932)
			(end -4.533392 -2.249932)
			(stroke
				(width 0.1524)
				(type default)
			)
			(layer "B.SilkS")
		)
		(fp_rect
			(start 5.39242 2.326132)
			(end 4.533392 -2.326132)
			(stroke
				(width 0)
				(type default)
			)
			(fill yes)
			(layer "B.SilkS")
		)
		(fp_line
			(start -3.750056 2.249932)
			(end 3.750056 2.249932)
			(stroke
				(width 0.1)
				(type default)
			)
			(layer "B.Fab")
		)
		(fp_line
			(start 3.750056 2.249932)
			(end 3.750056 -2.249932)
			(stroke
				(width 0.1)
				(type default)
			)
			(layer "B.Fab")
		)
		(fp_line
			(start -3.750056 -2.249932)
			(end -3.750056 2.249932)
			(stroke
				(width 0.1)
				(type default)
			)
			(layer "B.Fab")
		)
		(fp_line
			(start 3.750056 -2.249932)
			(end -3.750056 -2.249932)
			(stroke
				(width 0.1)
				(type default)
			)
			(layer "B.Fab")
		)
		(fp_text user "-"
			(at -4.956048 2.39776 270)
			(unlocked yes)
			(layer "B.SilkS")
			(effects
				(font
					(size 1.905 1.4224)
					(thickness 0.1524)
				)
				(justify left mirror)
			)
		)
		(fp_text user "+"
			(at 6.322314 0.786384 180)
			(unlocked yes)
			(layer "B.SilkS")
			(effects
				(font
					(size 1.905 1.4224)
					(thickness 0.1524)
				)
				(justify left mirror)
			)
		)
		(fp_text user "+"
			(at 6.322314 0.786384 180)
			(unlocked yes)
			(layer "B.Fab")
			(effects
				(font
					(size 1.905 1.4224)
					(thickness 0.1524)
				)
				(justify left mirror)
			)
		)
		(fp_text user "-"
			(at -4.8514 -0.14605 270)
			(unlocked yes)
			(layer "B.Fab")
			(effects
				(font
					(size 1.905 1.4224)
					(thickness 0.1524)
				)
				(justify left mirror)
			)
		)
		(pad "1" smd rect
			(at 3.199892 0 90)
			(size 2.413 2.8194)
			(layers "B.Cu" "B.Mask" "B.Paste")
			(net "PVDD11_S3_P1")
		)
		(pad "2" smd rect
			(at -3.199892 0 90)
			(size 2.413 2.8194)
			(layers "B.Cu" "B.Mask" "B.Paste")
			(net "GND")
		)
	)
	(footprint ""
		(layer "B.Cu")
		(at 373.314722 -416.899344 90)
		(property "Reference" "C6597"
			(at 0 0 90)
			(layer "B.SilkS")
			(hide yes)
			(effects
				(font
					(size 1.27 1.27)
				)
				(justify mirror)
			)
		)
		(property "Value" ""
			(at 0 0 90)
			(layer "B.Fab")
			(effects
				(font
					(size 1.27 1.27)
				)
				(justify mirror)
			)
		)
		(duplicate_pad_numbers_are_jumpers no)
		(fp_line
			(start 0.299974 -0.150114)
			(end -0.299974 -0.150114)
			(stroke
				(width 0.1)
				(type default)
			)
			(layer "B.Fab")
		)
		(fp_line
			(start -0.299974 -0.150114)
			(end -0.299974 0.150114)
			(stroke
				(width 0.1)
				(type default)
			)
			(layer "B.Fab")
		)
		(fp_line
			(start 0.299974 0.150114)
			(end 0.299974 -0.150114)
			(stroke
				(width 0.1)
				(type default)
			)
			(layer "B.Fab")
		)
		(fp_line
			(start -0.299974 0.150114)
			(end 0.299974 0.150114)
			(stroke
				(width 0.1)
				(type default)
			)
			(layer "B.Fab")
		)
		(pad "1" smd rect
			(at 0.2667 0 270)
			(size 0.3048 0.381)
			(layers "B.Cu" "B.Mask" "B.Paste")
			(net "P5E_CPU0_P3_TX_BUF_C_DP<0>")
		)
		(pad "2" smd rect
			(at -0.2667 0 270)
			(size 0.3048 0.381)
			(layers "B.Cu" "B.Mask" "B.Paste")
			(net "P5E_CPU0_P3_TX_BUF_DP<0>")
		)
	)
	(footprint ""
		(layer "B.Cu")
		(at 122.526806 -408.517344 90)
		(property "Reference" "C6730"
			(at 0 0 90)
			(layer "B.SilkS")
			(hide yes)
			(effects
				(font
					(size 1.27 1.27)
				)
				(justify mirror)
			)
		)
		(property "Value" ""
			(at 0 0 90)
			(layer "B.Fab")
			(effects
				(font
					(size 1.27 1.27)
				)
				(justify mirror)
			)
		)
		(duplicate_pad_numbers_are_jumpers no)
		(fp_line
			(start 0.299974 -0.150114)
			(end -0.299974 -0.150114)
			(stroke
				(width 0.1)
				(type default)
			)
			(layer "B.Fab")
		)
		(fp_line
			(start -0.299974 -0.150114)
			(end -0.299974 0.150114)
			(stroke
				(width 0.1)
				(type default)
			)
			(layer "B.Fab")
		)
		(fp_line
			(start 0.299974 0.150114)
			(end 0.299974 -0.150114)
			(stroke
				(width 0.1)
				(type default)
			)
			(layer "B.Fab")
		)
		(fp_line
			(start -0.299974 0.150114)
			(end 0.299974 0.150114)
			(stroke
				(width 0.1)
				(type default)
			)
			(layer "B.Fab")
		)
		(pad "1" smd rect
			(at 0.2667 0 270)
			(size 0.3048 0.381)
			(layers "B.Cu" "B.Mask" "B.Paste")
			(net "P5E_CPU1_P3_TX_BUF_C_DN<2>")
		)
		(pad "2" smd rect
			(at -0.2667 0 270)
			(size 0.3048 0.381)
			(layers "B.Cu" "B.Mask" "B.Paste")
			(net "P5E_CPU1_P3_TX_BUF_DN<2>")
		)
	)
	(footprint ""
		(layer "B.Cu")
		(at 130.104642 -78.52918)
		(property "Reference" "PC6025"
			(at 0 0 0)
			(layer "B.SilkS")
			(hide yes)
			(effects
				(font
					(size 1.27 1.27)
				)
				(justify mirror)
			)
		)
		(property "Value" ""
			(at 0 0 0)
			(layer "B.Fab")
			(effects
				(font
					(size 1.27 1.27)
				)
				(justify mirror)
			)
		)
		(duplicate_pad_numbers_are_jumpers no)
		(fp_line
			(start -1.524 -0.762)
			(end -1.524 0.762)
			(stroke
				(width 0.1524)
				(type default)
			)
			(layer "B.SilkS")
		)
		(fp_line
			(start -1.524 0.762)
			(end 1.524 0.762)
			(stroke
				(width 0.1524)
				(type default)
			)
			(layer "B.SilkS")
		)
		(fp_line
			(start 1.524 -0.762)
			(end -1.524 -0.762)
			(stroke
				(width 0.1524)
				(type default)
			)
			(layer "B.SilkS")
		)
		(fp_line
			(start 1.524 0.762)
			(end 1.524 -0.762)
			(stroke
				(width 0.1524)
				(type default)
			)
			(layer "B.SilkS")
		)
		(fp_line
			(start -1.1049 -0.724916)
			(end 1.1049 -0.724916)
			(stroke
				(width 0.1)
				(type default)
			)
			(layer "B.Fab")
		)
		(fp_line
			(start -1.1049 0.724916)
			(end -1.1049 -0.724916)
			(stroke
				(width 0.1)
				(type default)
			)
			(layer "B.Fab")
		)
		(fp_line
			(start 1.1049 -0.724916)
			(end 1.1049 0.724916)
			(stroke
				(width 0.1)
				(type default)
			)
			(layer "B.Fab")
		)
		(fp_line
			(start 1.1049 0.724916)
			(end -1.1049 0.724916)
			(stroke
				(width 0.1)
				(type default)
			)
			(layer "B.Fab")
		)
		(pad "1" smd rect
			(at 0.889 0)
			(size 1.016 1.27)
			(layers "B.Cu" "B.Mask" "B.Paste")
			(net "P1V2_AUX")
		)
		(pad "2" smd rect
			(at -0.889 0)
			(size 1.016 1.27)
			(layers "B.Cu" "B.Mask" "B.Paste")
			(net "GND")
		)
	)
)
